FILE_TYPE = MACRO_DRAWING;
SET COLOR_WIRE YELLOW;
SET COLOR_PROP ORANGE;
SET COLOR_DOT WHITE;
SET COLOR_ARC YELLOW;
SET COLOR_BODY GREEN;
SET COLOR_NOTE PURPLE;
SET PROP_DISPLAY VALUE;
SET PAGE_NUMBER P269;
FORCEADD QUANTA_TITLE_BLOCK_C..1
(-100 100);
FORCEPROP 1 LAST CUSTOM_TXT_CDS <NAME_2>
J 0
(-3275 150);
FORCEPROP 1 LAST CUSTOM_TXT_CDS <NAME_1>
J 0
(-3275 275);
FORCEPROP 1 LAST CUSTOM_TXT_CDS <Q_NUMBER>
J 0
(-1503 203);
DISPLAY 1.212766 (-1503 203);
FORCEPROP 1 LAST CUSTOM_TXT_CDS <Q_PROJ>
J 0
(-2482 202);
DISPLAY 1.212766 (-2482 202);
FORCEPROP 1 LAST CUSTOM_TXT_CDS <Q_REV>
J 0
(-284 203);
DISPLAY 1.212766 (-284 203);
FORCEPROP 1 LAST CUSTOM_TXT_CDS <CON_LAST_MODIFIED>
J 0
(-1985 115);
DISPLAY 0.978723 (-1985 115);
FORCEPROP 1 LAST CUSTOM_TXT_CDS <CON_PAGE_NUM> OF <CON_TOTAL_PAGES>
J 0
(-546 118);
DISPLAY 0.978723 (-546 118);
FORCEPROP 1 LAST Q_TITLE BLANK
J 0
(-9466 126);
DISPLAY 2.446809 (-9466 126);
PAINT GREEN (-9466 126);
FORCEPROP 1 LAST Q_DEPT 
J 1
(-3863 149);
DISPLAY 1.957447 (-3863 149);
PAINT GREEN (-3863 149);
FORCEPROP 2 LAST CDS_XR_PAGE_TITLE CR-283 : @S9S_MB_2U_LIB.S9S_MB_2U(SCH_1):PAGE283
J 0
(-7990 5350);
DISPLAY 0.638298 (-7990 5350);
PAINT PINK (-7990 5350);
DISPLAY INVISIBLE (-7990 5350);
FORCEPROP 2 LAST CDS_LIB pure_quanta
J 0
(-100 100);
DISPLAY INVISIBLE (-100 100);
FORCEPROP 1 LAST CDS_LMAN_SYM_OUTLINE -9475,6775,100,-125
J 0
(-100 100);
DISPLAY 0.468085 (-100 100);
PAINT GREEN (-100 100);
DISPLAY INVISIBLE (-100 100);
FORCEPROP 2 LAST PAGE_BORDER TRUE
J 0
(-7990 5350);
DISPLAY 0.638298 (-7990 5350);
PAINT PINK (-7990 5350);
DISPLAY INVISIBLE (-7990 5350);
FORCEPROP 1 LAST COMMENT_BODY TRUE
J 0
(-88 87);
DISPLAY 0.978723 (-88 87);
PAINT GREEN (-88 87);
DISPLAY INVISIBLE (-88 87);
FORCEPROP 2 LAST CUSTOM_TXT_CDS <XR_PAGE_TITLE>
J 0
(-7990 5350);
DISPLAY 0.638298 (-7990 5350);
PAINT PINK (-7990 5350);
DISPLAY INVISIBLE (-7990 5350);
FORCEPROP 0 LAST CDS_CON_LAST_MODIFIED Thu Aug 24 16:16:45 2023
J 0
(-1985 115);
DISPLAY INVISIBLE (-1985 115);
FORCENOTE
THIS PAGE WAS INTENTIONALLY LEFT BLANK
(-9125 3300) 0;
DISPLAY LEFT (-9125 3300);
DISPLAY 4.914894 (-9125 3300);
QUIT
